# S9S_MB_2U (Grand Teton) — schematic netlist excerpt (pin names and nets, part order shuffled) for the footprints in the layout excerpt that follows; sources: Cadence DE-HDL packaged netlist, KiCad conversion of 03242023_DA0F0TMBIJ0_F0T_Motherboard_J_brd_V01_OCP.brd

C1880  Q_CAP  0.1UF 25V 10% X7R  pkg 0402  page 165 : A = P3V3_AUX ; B = GND
C2286  Q_CAP  0.1UF 25V 10% X7R  pkg 0402  page 169 : A = P3V3_AUX_USB_BUF ; B = GND

(kicad_pcb
	(version 20260206)
	(generator "pcbnew")
	(generator_version "10.0")
	(general
		(thickness 1.6)
		(legacy_teardrops no)
	)
	(paper "A4")
	(title_block
		(title "03242023_DA0F0TMBIJ0_F0T_Motherboard_J_brd_V01_OCP.brd")
		(comment 1 "Grand Teton / footprints 185-186 of 6105")
	)
	(layers
		(0 "F.Cu" signal "TOP")
		(4 "In1.Cu" signal "GND")
		(6 "In2.Cu" signal "IN1")
		(8 "In3.Cu" signal "GND1")
		(10 "In4.Cu" signal "IN2")
		(12 "In5.Cu" signal "GND2")
		(14 "In6.Cu" signal "IN3")
		(16 "In7.Cu" signal "GND3")
		(18 "In8.Cu" signal "VCC")
		(20 "In9.Cu" signal "VCC1")
		(22 "In10.Cu" signal "GND4")
		(24 "In11.Cu" signal "IN4")
		(26 "In12.Cu" signal "GND5")
		(28 "In13.Cu" signal "IN5")
		(30 "In14.Cu" signal "GND6")
		(32 "In15.Cu" signal "IN6")
		(34 "In16.Cu" signal "GND7")
		(2 "B.Cu" signal "BOTTOM")
		(9 "F.Adhes" user "F.Adhesive")
		(11 "B.Adhes" user "B.Adhesive")
		(13 "F.Paste" user "Package Geometry/Pastemask Top")
		(15 "B.Paste" user "Package Geometry/Pastemask Bottom")
		(5 "F.SilkS" user "Ref Des/Silkscreen Top")
		(7 "B.SilkS" user "Ref Des/Silkscreen Bottom")
		(1 "F.Mask" user "Board Geometry/Soldermask Top")
		(3 "B.Mask" user "Board Geometry/Soldermask Bottom")
		(17 "Dwgs.User" user "User.Drawings")
		(19 "Cmts.User" user "User.Comments")
		(21 "Eco1.User" user "User.Eco1")
		(23 "Eco2.User" user "User.Eco2")
		(25 "Edge.Cuts" user "Board Geometry/Outline")
		(27 "Margin" user)
		(31 "F.CrtYd" user "Package Geometry/Place Bound Top")
		(29 "B.CrtYd" user "Package Geometry/Place Bound Bottom")
		(35 "F.Fab" user "Ref Des/Assembly Top")
		(33 "B.Fab" user "Ref Des/Assembly Bottom")
	)
	(footprint ""
		(layer "F.Cu")
		(at 127.27432 -23.769828)
		(property "Reference" "C2286"
			(at 0 0 0)
			(layer "F.SilkS")
			(hide yes)
			(effects
				(font
					(size 1.27 1.27)
				)
			)
		)
		(property "Value" ""
			(at 0 0 0)
			(layer "F.Fab")
			(effects
				(font
					(size 1.27 1.27)
				)
			)
		)
		(duplicate_pad_numbers_are_jumpers no)
		(fp_line
			(start -0.7874 -0.4064)
			(end 0.7874 -0.4064)
			(stroke
				(width 0.1524)
				(type default)
			)
			(layer "F.SilkS")
		)
		(fp_line
			(start -0.7874 0.4064)
			(end -0.7874 -0.4064)
			(stroke
				(width 0.1524)
				(type default)
			)
			(layer "F.SilkS")
		)
		(fp_line
			(start 0.7874 -0.4064)
			(end 0.7874 0.4064)
			(stroke
				(width 0.1524)
				(type default)
			)
			(layer "F.SilkS")
		)
		(fp_line
			(start 0.7874 0.4064)
			(end -0.7874 0.4064)
			(stroke
				(width 0.1524)
				(type default)
			)
			(layer "F.SilkS")
		)
		(fp_line
			(start -0.67945 -0.305054)
			(end -0.12065 -0.305054)
			(stroke
				(width 0.1)
				(type default)
			)
			(layer "F.Fab")
		)
		(fp_line
			(start -0.67945 0.3048)
			(end -0.67945 -0.305054)
			(stroke
				(width 0.1)
				(type default)
			)
			(layer "F.Fab")
		)
		(fp_line
			(start -0.12065 -0.305054)
			(end -0.12065 -0.2794)
			(stroke
				(width 0.1)
				(type default)
			)
			(layer "F.Fab")
		)
		(fp_line
			(start -0.12065 -0.2794)
			(end 0.12065 -0.2794)
			(stroke
				(width 0.1)
				(type default)
			)
			(layer "F.Fab")
		)
		(fp_line
			(start -0.12065 0.2794)
			(end -0.12065 0.3048)
			(stroke
				(width 0.1)
				(type default)
			)
			(layer "F.Fab")
		)
		(fp_line
			(start -0.12065 0.3048)
			(end -0.67945 0.3048)
			(stroke
				(width 0.1)
				(type default)
			)
			(layer "F.Fab")
		)
		(fp_line
			(start 0.120396 0.2794)
			(end -0.12065 0.2794)
			(stroke
				(width 0.1)
				(type default)
			)
			(layer "F.Fab")
		)
		(fp_line
			(start 0.120396 0.3048)
			(end 0.120396 0.2794)
			(stroke
				(width 0.1)
				(type default)
			)
			(layer "F.Fab")
		)
		(fp_line
			(start 0.12065 -0.3048)
			(end 0.67945 -0.3048)
			(stroke
				(width 0.1)
				(type default)
			)
			(layer "F.Fab")
		)
		(fp_line
			(start 0.12065 -0.2794)
			(end 0.12065 -0.3048)
			(stroke
				(width 0.1)
				(type default)
			)
			(layer "F.Fab")
		)
		(fp_line
			(start 0.67945 -0.3048)
			(end 0.67945 0.3048)
			(stroke
				(width 0.1)
				(type default)
			)
			(layer "F.Fab")
		)
		(fp_line
			(start 0.67945 0.3048)
			(end 0.120396 0.3048)
			(stroke
				(width 0.1)
				(type default)
			)
			(layer "F.Fab")
		)
		(pad "1" smd circle
			(at -0.40005 0)
			(size 0 0)
			(layers "F.Cu" "F.Mask" "F.Paste")
			(net "P3V3_AUX_USB_BUF")
		)
		(pad "2" smd circle
			(at 0.40005 0)
			(size 0 0)
			(layers "F.Cu" "F.Mask" "F.Paste")
			(net "GND")
		)
	)
	(footprint ""
		(layer "F.Cu")
		(at 139.43838 -38.049708)
		(property "Reference" "C1880"
			(at 0 0 0)
			(layer "F.SilkS")
			(hide yes)
			(effects
				(font
					(size 1.27 1.27)
				)
			)
		)
		(property "Value" ""
			(at 0 0 0)
			(layer "F.Fab")
			(effects
				(font
					(size 1.27 1.27)
				)
			)
		)
		(duplicate_pad_numbers_are_jumpers no)
		(fp_line
			(start -0.7874 -0.4064)
			(end 0.7874 -0.4064)
			(stroke
				(width 0.1524)
				(type default)
			)
			(layer "F.SilkS")
		)
		(fp_line
			(start -0.7874 0.4064)
			(end -0.7874 -0.4064)
			(stroke
				(width 0.1524)
				(type default)
			)
			(layer "F.SilkS")
		)
		(fp_line
			(start 0.7874 -0.4064)
			(end 0.7874 0.4064)
			(stroke
				(width 0.1524)
				(type default)
			)
			(layer "F.SilkS")
		)
		(fp_line
			(start 0.7874 0.4064)
			(end -0.7874 0.4064)
			(stroke
				(width 0.1524)
				(type default)
			)
			(layer "F.SilkS")
		)
		(fp_line
			(start -0.67945 -0.305054)
			(end -0.12065 -0.305054)
			(stroke
				(width 0.1)
				(type default)
			)
			(layer "F.Fab")
		)
		(fp_line
			(start -0.67945 0.3048)
			(end -0.67945 -0.305054)
			(stroke
				(width 0.1)
				(type default)
			)
			(layer "F.Fab")
		)
		(fp_line
			(start -0.12065 -0.305054)
			(end -0.12065 -0.2794)
			(stroke
				(width 0.1)
				(type default)
			)
			(layer "F.Fab")
		)
		(fp_line
			(start -0.12065 -0.2794)
			(end 0.12065 -0.2794)
			(stroke
				(width 0.1)
				(type default)
			)
			(layer "F.Fab")
		)
		(fp_line
			(start -0.12065 0.2794)
			(end -0.12065 0.3048)
			(stroke
				(width 0.1)
				(type default)
			)
			(layer "F.Fab")
		)
		(fp_line
			(start -0.12065 0.3048)
			(end -0.67945 0.3048)
			(stroke
				(width 0.1)
				(type default)
			)
			(layer "F.Fab")
		)
		(fp_line
			(start 0.120396 0.2794)
			(end -0.12065 0.2794)
			(stroke
				(width 0.1)
				(type default)
			)
			(layer "F.Fab")
		)
		(fp_line
			(start 0.120396 0.3048)
			(end 0.120396 0.2794)
			(stroke
				(width 0.1)
				(type default)
			)
			(layer "F.Fab")
		)
		(fp_line
			(start 0.12065 -0.3048)
			(end 0.67945 -0.3048)
			(stroke
				(width 0.1)
				(type default)
			)
			(layer "F.Fab")
		)
		(fp_line
			(start 0.12065 -0.2794)
			(end 0.12065 -0.3048)
			(stroke
				(width 0.1)
				(type default)
			)
			(layer "F.Fab")
		)
		(fp_line
			(start 0.67945 -0.3048)
			(end 0.67945 0.3048)
			(stroke
				(width 0.1)
				(type default)
			)
			(layer "F.Fab")
		)
		(fp_line
			(start 0.67945 0.3048)
			(end 0.120396 0.3048)
			(stroke
				(width 0.1)
				(type default)
			)
			(layer "F.Fab")
		)
		(pad "1" smd circle
			(at -0.40005 0)
			(size 0 0)
			(layers "F.Cu" "F.Mask" "F.Paste")
			(net "P3V3_AUX")
		)
		(pad "2" smd circle
			(at 0.40005 0)
			(size 0 0)
			(layers "F.Cu" "F.Mask" "F.Paste")
			(net "GND")
		)
	)
)
